(kicad_pcb
	(version 20260206)
	(generator "pcbnew")
	(generator_version "10.0")
	(general
		(thickness 1.6)
		(legacy_teardrops no)
	)
	(paper "A4")
	(title_block
		(title "pdpb — Lightning_PDPB_BRD.brd")
		(comment 1 "Lightning (Wiwynn / Facebook NVMe JBOF) / footprints 599-605 of 1140")
	)
	(layers
		(0 "F.Cu" signal "TOP")
		(4 "In1.Cu" signal "L2GND")
		(6 "In2.Cu" signal "L3")
		(8 "In3.Cu" signal "L4VCC")
		(10 "In4.Cu" signal "L5VCC")
		(12 "In5.Cu" signal "L6")
		(14 "In6.Cu" signal "L7GND")
		(2 "B.Cu" signal "BOTTOM")
		(9 "F.Adhes" user "F.Adhesive")
		(11 "B.Adhes" user "B.Adhesive")
		(13 "F.Paste" user "Package Geometry/Pastemask Top")
		(15 "B.Paste" user "Package Geometry/Pastemask Bottom")
		(5 "F.SilkS" user "Ref Des/Silkscreen Top")
		(7 "B.SilkS" user "Ref Des/Silkscreen Bottom")
		(1 "F.Mask" user "Board Geometry/Soldermask Top")
		(3 "B.Mask" user "Board Geometry/Soldermask Bottom")
		(17 "Dwgs.User" user "User.Drawings")
		(19 "Cmts.User" user "User.Comments")
		(21 "Eco1.User" user "User.Eco1")
		(23 "Eco2.User" user "User.Eco2")
		(25 "Edge.Cuts" user "Board Geometry/Outline")
		(27 "Margin" user)
		(31 "F.CrtYd" user "Package Geometry/Place Bound Top")
		(29 "B.CrtYd" user "Package Geometry/Place Bound Bottom")
		(35 "F.Fab" user "Ref Des/Assembly Top")
		(33 "B.Fab" user "Ref Des/Assembly Bottom")
	)
	(footprint ""
		(layer "F.Cu")
		(at 30.607 -308.0004 90)
		(property "Reference" "Q81"
			(at 0 0 90)
			(layer "F.SilkS")
			(hide yes)
			(effects
				(font
					(size 1.27 1.27)
				)
			)
		)
		(property "Value" "2N7002A-7-GP"
			(at 0.127 -8.9662 90)
			(unlocked yes)
			(layer "F.Fab")
			(hide yes)
			(effects
				(font
					(size 1.016 1.016)
					(thickness 0.1524)
				)
			)
		)
		(property "Device Type" "SOT23DGS2D4H48"
			(at 0.127 -10.4902 90)
			(unlocked yes)
			(layer "F.Fab")
			(hide yes)
			(effects
				(font
					(size 1.016 1.016)
					(thickness 0.1524)
				)
			)
		)
		(duplicate_pad_numbers_are_jumpers no)
		(fp_line
			(start 1.651 -1.778)
			(end -1.651 -1.778)
			(stroke
				(width 0.1524)
				(type default)
			)
			(layer "F.SilkS")
		)
		(fp_line
			(start -1.651 -1.778)
			(end -1.651 1.778)
			(stroke
				(width 0.1524)
				(type default)
			)
			(layer "F.SilkS")
		)
		(fp_line
			(start 1.651 1.778)
			(end 1.651 -1.778)
			(stroke
				(width 0.1524)
				(type default)
			)
			(layer "F.SilkS")
		)
		(fp_line
			(start -1.651 1.778)
			(end 1.651 1.778)
			(stroke
				(width 0.1524)
				(type default)
			)
			(layer "F.SilkS")
		)
		(fp_poly
			(pts
				(xy -1.778 1.8796) (xy -1.778 -1.8796) (xy 1.778 -1.8796) (xy 1.778 1.8796)
			)
			(stroke
				(width 0)
				(type default)
			)
			(fill no)
			(layer "F.CrtYd")
		)
		(fp_poly
			(pts
				(xy -1.778 1.8796) (xy -1.778 -1.8796) (xy 1.778 -1.8796) (xy 1.778 1.8796)
			)
			(stroke
				(width 0)
				(type default)
			)
			(fill no)
			(layer "F.Fab")
		)
		(pad "D" smd custom
			(at 0 -0.9525 90)
			(size 0.1905 0.1905)
			(layers "F.Cu" "F.Mask" "F.Paste")
			(net "P12V_MOST11_GATE_D")
			(options
				(clearance outline)
				(anchor circle)
			)
			(primitives
				(gr_poly
					(pts
						(arc
							(start -0.1778 0.5715)
							(mid -0.321484 0.511984)
							(end -0.381 0.3683)
						)
						(arc
							(start -0.381 -0.3683)
							(mid -0.321484 -0.511984)
							(end -0.1778 -0.5715)
						)
						(arc
							(start 0.1778 -0.5715)
							(mid 0.321484 -0.511984)
							(end 0.381 -0.3683)
						)
						(arc
							(start 0.381 0.3683)
							(mid 0.321484 0.511984)
							(end 0.1778 0.5715)
						)
					)
					(width 0)
					(fill yes)
				)
			)
		)
		(pad "G" smd custom
			(at -0.98425 0.9525 90)
			(size 0.1905 0.1905)
			(layers "F.Cu" "F.Mask" "F.Paste")
			(net "P12V_MOST11_GATE")
			(options
				(clearance outline)
				(anchor circle)
			)
			(primitives
				(gr_poly
					(pts
						(arc
							(start -0.1778 0.5715)
							(mid -0.321484 0.511984)
							(end -0.381 0.3683)
						)
						(arc
							(start -0.381 -0.3683)
							(mid -0.321484 -0.511984)
							(end -0.1778 -0.5715)
						)
						(arc
							(start 0.1778 -0.5715)
							(mid 0.321484 -0.511984)
							(end 0.381 -0.3683)
						)
						(arc
							(start 0.381 0.3683)
							(mid 0.321484 0.511984)
							(end 0.1778 0.5715)
						)
					)
					(width 0)
					(fill yes)
				)
			)
		)
		(pad "S" smd custom
			(at 0.98425 0.9525 90)
			(size 0.1905 0.1905)
			(layers "F.Cu" "F.Mask" "F.Paste")
			(net "GND")
			(options
				(clearance outline)
				(anchor circle)
			)
			(primitives
				(gr_poly
					(pts
						(arc
							(start -0.1778 0.5715)
							(mid -0.321484 0.511984)
							(end -0.381 0.3683)
						)
						(arc
							(start -0.381 -0.3683)
							(mid -0.321484 -0.511984)
							(end -0.1778 -0.5715)
						)
						(arc
							(start 0.1778 -0.5715)
							(mid 0.321484 -0.511984)
							(end 0.381 -0.3683)
						)
						(arc
							(start 0.381 0.3683)
							(mid 0.321484 0.511984)
							(end 0.1778 0.5715)
						)
					)
					(width 0)
					(fill yes)
				)
			)
		)
	)
	(footprint ""
		(layer "F.Cu")
		(at 208.153 -396.113)
		(property "Reference" "R552"
			(at 0 0 0)
			(layer "F.SilkS")
			(hide yes)
			(effects
				(font
					(size 1.27 1.27)
				)
			)
		)
		(property "Value" "200KR2F-L-GP"
			(at 0.064008 -3.993896 0)
			(unlocked yes)
			(layer "F.Fab")
			(hide yes)
			(effects
				(font
					(size 1.016 1.016)
					(thickness 0.1524)
				)
			)
		)
		(property "Device Type" "R402H16"
			(at 0.064008 -5.517896 0)
			(unlocked yes)
			(layer "F.Fab")
			(hide yes)
			(effects
				(font
					(size 1.016 1.016)
					(thickness 0.1524)
				)
			)
		)
		(duplicate_pad_numbers_are_jumpers no)
		(fp_line
			(start -0.508 -0.9398)
			(end -0.508 0.9398)
			(stroke
				(width 0.1524)
				(type default)
			)
			(layer "F.SilkS")
		)
		(fp_line
			(start 0.508 -0.9398)
			(end -0.508 -0.9398)
			(stroke
				(width 0.1524)
				(type default)
			)
			(layer "F.SilkS")
		)
		(fp_rect
			(start -0.508 0.9398)
			(end 0.508 -0.9398)
			(stroke
				(width 0)
				(type default)
			)
			(fill no)
			(layer "F.CrtYd")
		)
		(fp_rect
			(start -0.508 0.9398)
			(end 0.508 -0.9398)
			(stroke
				(width 0)
				(type default)
			)
			(fill no)
			(layer "F.Fab")
		)
		(pad "1" smd custom
			(at 0 -0.4445)
			(size 0.1397 0.1397)
			(layers "F.Cu" "F.Mask" "F.Paste")
			(net "SW_SSD1_R")
			(options
				(clearance outline)
				(anchor circle)
			)
			(primitives
				(gr_poly
					(pts
						(arc
							(start -0.1778 -0.2794)
							(mid -0.249642 -0.249642)
							(end -0.2794 -0.1778)
						)
						(arc
							(start -0.2794 0.1778)
							(mid -0.249642 0.249642)
							(end -0.1778 0.2794)
						)
						(arc
							(start 0.1778 0.2794)
							(mid 0.249642 0.249642)
							(end 0.2794 0.1778)
						)
						(arc
							(start 0.2794 -0.1778)
							(mid 0.249642 -0.249642)
							(end 0.1778 -0.2794)
						)
					)
					(width 0)
					(fill yes)
				)
			)
		)
		(pad "2" smd custom
			(at 0 0.4445)
			(size 0.1397 0.1397)
			(layers "F.Cu" "F.Mask" "F.Paste")
			(net "SW_SSD1_N")
			(options
				(clearance outline)
				(anchor circle)
			)
			(primitives
				(gr_poly
					(pts
						(arc
							(start -0.1778 -0.2794)
							(mid -0.249642 -0.249642)
							(end -0.2794 -0.1778)
						)
						(arc
							(start -0.2794 0.1778)
							(mid -0.249642 0.249642)
							(end -0.1778 0.2794)
						)
						(arc
							(start 0.1778 0.2794)
							(mid 0.249642 0.249642)
							(end 0.2794 0.1778)
						)
						(arc
							(start 0.2794 -0.1778)
							(mid 0.249642 -0.249642)
							(end 0.1778 -0.2794)
						)
					)
					(width 0)
					(fill yes)
				)
			)
		)
	)
	(footprint ""
		(layer "F.Cu")
		(at 29.972 -374.65 180)
		(property "Reference" "R332"
			(at 0 0 180)
			(layer "F.SilkS")
			(hide yes)
			(effects
				(font
					(size 1.27 1.27)
				)
			)
		)
		(property "Value" "4K7R2J-2-GP"
			(at 0.064008 -3.993896 180)
			(unlocked yes)
			(layer "F.Fab")
			(hide yes)
			(effects
				(font
					(size 1.016 1.016)
					(thickness 0.1524)
				)
			)
		)
		(property "Device Type" "R402H16"
			(at 0.064008 -5.517896 180)
			(unlocked yes)
			(layer "F.Fab")
			(hide yes)
			(effects
				(font
					(size 1.016 1.016)
					(thickness 0.1524)
				)
			)
		)
		(duplicate_pad_numbers_are_jumpers no)
		(fp_line
			(start 0.508 -0.9398)
			(end -0.508 -0.9398)
			(stroke
				(width 0.1524)
				(type default)
			)
			(layer "F.SilkS")
		)
		(fp_line
			(start -0.508 -0.9398)
			(end -0.508 0.9398)
			(stroke
				(width 0.1524)
				(type default)
			)
			(layer "F.SilkS")
		)
		(fp_rect
			(start -0.508 0.9398)
			(end 0.508 -0.9398)
			(stroke
				(width 0)
				(type default)
			)
			(fill no)
			(layer "F.CrtYd")
		)
		(fp_rect
			(start -0.508 0.9398)
			(end 0.508 -0.9398)
			(stroke
				(width 0)
				(type default)
			)
			(fill no)
			(layer "F.Fab")
		)
		(pad "1" smd custom
			(at 0 -0.4445 180)
			(size 0.1397 0.1397)
			(layers "F.Cu" "F.Mask" "F.Paste")
			(net "P3V3")
			(options
				(clearance outline)
				(anchor circle)
			)
			(primitives
				(gr_poly
					(pts
						(arc
							(start -0.1778 -0.2794)
							(mid -0.249642 -0.249642)
							(end -0.2794 -0.1778)
						)
						(arc
							(start -0.2794 0.1778)
							(mid -0.249642 0.249642)
							(end -0.1778 0.2794)
						)
						(arc
							(start 0.1778 0.2794)
							(mid 0.249642 0.249642)
							(end 0.2794 0.1778)
						)
						(arc
							(start 0.2794 -0.1778)
							(mid 0.249642 -0.249642)
							(end 0.1778 -0.2794)
						)
					)
					(width 0)
					(fill yes)
				)
			)
		)
		(pad "2" smd custom
			(at 0 0.4445 180)
			(size 0.1397 0.1397)
			(layers "F.Cu" "F.Mask" "F.Paste")
			(net "I2C_B_TMP4_A1")
			(options
				(clearance outline)
				(anchor circle)
			)
			(primitives
				(gr_poly
					(pts
						(arc
							(start -0.1778 -0.2794)
							(mid -0.249642 -0.249642)
							(end -0.2794 -0.1778)
						)
						(arc
							(start -0.2794 0.1778)
							(mid -0.249642 0.249642)
							(end -0.1778 0.2794)
						)
						(arc
							(start 0.1778 0.2794)
							(mid 0.249642 0.249642)
							(end 0.2794 0.1778)
						)
						(arc
							(start 0.2794 -0.1778)
							(mid 0.249642 -0.249642)
							(end 0.1778 -0.2794)
						)
					)
					(width 0)
					(fill yes)
				)
			)
		)
	)
	(footprint ""
		(layer "F.Cu")
		(at 106.045 -308.229 180)
		(property "Reference" "C9353"
			(at 0 0 180)
			(layer "F.SilkS")
			(hide yes)
			(effects
				(font
					(size 1.27 1.27)
				)
			)
		)
		(property "Value" "SC1KP50V2KX-1GP"
			(at 1.1811 -2.7051 180)
			(unlocked yes)
			(layer "F.Fab")
			(hide yes)
			(effects
				(font
					(size 1.016 1.016)
					(thickness 0.1524)
				)
			)
		)
		(property "Device Type" "C402H22"
			(at 1.1811 -4.2291 180)
			(unlocked yes)
			(layer "F.Fab")
			(hide yes)
			(effects
				(font
					(size 1.016 1.016)
					(thickness 0.1524)
				)
			)
		)
		(duplicate_pad_numbers_are_jumpers no)
		(fp_rect
			(start -0.4318 0.9525)
			(end 0.4318 -0.9525)
			(stroke
				(width 0)
				(type default)
			)
			(fill no)
			(layer "F.CrtYd")
		)
		(fp_rect
			(start -0.4318 0.9525)
			(end 0.4318 -0.9525)
			(stroke
				(width 0)
				(type default)
			)
			(fill no)
			(layer "F.Fab")
		)
		(pad "1" smd custom
			(at 0 -0.4445 180)
			(size 0.1524 0.1524)
			(layers "F.Cu" "F.Mask" "F.Paste")
			(net "SSD_PRSNT1")
			(options
				(clearance outline)
				(anchor circle)
			)
			(primitives
				(gr_poly
					(pts
						(arc
							(start 0.3048 -0.2032)
							(mid 0.275042 -0.275042)
							(end 0.2032 -0.3048)
						)
						(arc
							(start -0.2032 -0.3048)
							(mid -0.275042 -0.275042)
							(end -0.3048 -0.2032)
						)
						(arc
							(start -0.3048 0.2032)
							(mid -0.275042 0.275042)
							(end -0.2032 0.3048)
						)
						(arc
							(start 0.2032 0.3048)
							(mid 0.275042 0.275042)
							(end 0.3048 0.2032)
						)
					)
					(width 0)
					(fill yes)
				)
			)
		)
		(pad "2" smd custom
			(at 0 0.4445 180)
			(size 0.1524 0.1524)
			(layers "F.Cu" "F.Mask" "F.Paste")
			(net "GND")
			(options
				(clearance outline)
				(anchor circle)
			)
			(primitives
				(gr_poly
					(pts
						(arc
							(start 0.3048 -0.2032)
							(mid 0.275042 -0.275042)
							(end 0.2032 -0.3048)
						)
						(arc
							(start -0.2032 -0.3048)
							(mid -0.275042 -0.275042)
							(end -0.3048 -0.2032)
						)
						(arc
							(start -0.3048 0.2032)
							(mid -0.275042 0.275042)
							(end -0.2032 0.3048)
						)
						(arc
							(start 0.2032 0.3048)
							(mid 0.275042 0.275042)
							(end 0.3048 0.2032)
						)
					)
					(width 0)
					(fill yes)
				)
			)
		)
	)
	(footprint ""
		(layer "F.Cu")
		(at 99.949 -299.593 180)
		(property "Reference" "C8850"
			(at 0 0 180)
			(layer "F.SilkS")
			(hide yes)
			(effects
				(font
					(size 1.27 1.27)
				)
			)
		)
		(property "Value" "SCD1U16V2KX-3GP"
			(at 1.1811 -2.7051 180)
			(unlocked yes)
			(layer "F.Fab")
			(hide yes)
			(effects
				(font
					(size 1.016 1.016)
					(thickness 0.1524)
				)
			)
		)
		(property "Device Type" "C402H22"
			(at 1.1811 -4.2291 180)
			(unlocked yes)
			(layer "F.Fab")
			(hide yes)
			(effects
				(font
					(size 1.016 1.016)
					(thickness 0.1524)
				)
			)
		)
		(duplicate_pad_numbers_are_jumpers no)
		(fp_rect
			(start -0.4318 0.9525)
			(end 0.4318 -0.9525)
			(stroke
				(width 0)
				(type default)
			)
			(fill no)
			(layer "F.CrtYd")
		)
		(fp_rect
			(start -0.4318 0.9525)
			(end 0.4318 -0.9525)
			(stroke
				(width 0)
				(type default)
			)
			(fill no)
			(layer "F.Fab")
		)
		(pad "1" smd custom
			(at 0 -0.4445 180)
			(size 0.1524 0.1524)
			(layers "F.Cu" "F.Mask" "F.Paste")
			(net "VDD_IO_2")
			(options
				(clearance outline)
				(anchor circle)
			)
			(primitives
				(gr_poly
					(pts
						(arc
							(start 0.3048 -0.2032)
							(mid 0.275042 -0.275042)
							(end 0.2032 -0.3048)
						)
						(arc
							(start -0.2032 -0.3048)
							(mid -0.275042 -0.275042)
							(end -0.3048 -0.2032)
						)
						(arc
							(start -0.3048 0.2032)
							(mid -0.275042 0.275042)
							(end -0.2032 0.3048)
						)
						(arc
							(start 0.2032 0.3048)
							(mid 0.275042 0.275042)
							(end 0.3048 0.2032)
						)
					)
					(width 0)
					(fill yes)
				)
			)
		)
		(pad "2" smd custom
			(at 0 0.4445 180)
			(size 0.1524 0.1524)
			(layers "F.Cu" "F.Mask" "F.Paste")
			(net "GND")
			(options
				(clearance outline)
				(anchor circle)
			)
			(primitives
				(gr_poly
					(pts
						(arc
							(start 0.3048 -0.2032)
							(mid 0.275042 -0.275042)
							(end 0.2032 -0.3048)
						)
						(arc
							(start -0.2032 -0.3048)
							(mid -0.275042 -0.275042)
							(end -0.3048 -0.2032)
						)
						(arc
							(start -0.3048 0.2032)
							(mid -0.275042 0.275042)
							(end -0.2032 0.3048)
						)
						(arc
							(start 0.2032 0.3048)
							(mid 0.275042 0.275042)
							(end 0.3048 0.2032)
						)
					)
					(width 0)
					(fill yes)
				)
			)
		)
	)
	(footprint ""
		(layer "F.Cu")
		(at 99.187 -224.282)
		(property "Reference" "R9602"
			(at 0 0 0)
			(layer "F.SilkS")
			(hide yes)
			(effects
				(font
					(size 1.27 1.27)
				)
			)
		)
		(property "Value" "10R2F-L-GP"
			(at 0.064008 -3.993896 0)
			(unlocked yes)
			(layer "F.Fab")
			(hide yes)
			(effects
				(font
					(size 1.016 1.016)
					(thickness 0.1524)
				)
			)
		)
		(property "Device Type" "R402H14"
			(at 0.064008 -5.517896 0)
			(unlocked yes)
			(layer "F.Fab")
			(hide yes)
			(effects
				(font
					(size 1.016 1.016)
					(thickness 0.1524)
				)
			)
		)
		(duplicate_pad_numbers_are_jumpers no)
		(fp_line
			(start -0.508 -0.9398)
			(end -0.508 0.9398)
			(stroke
				(width 0.1524)
				(type default)
			)
			(layer "F.SilkS")
		)
		(fp_line
			(start 0.508 -0.9398)
			(end -0.508 -0.9398)
			(stroke
				(width 0.1524)
				(type default)
			)
			(layer "F.SilkS")
		)
		(fp_rect
			(start -0.508 0.9398)
			(end 0.508 -0.9398)
			(stroke
				(width 0)
				(type default)
			)
			(fill no)
			(layer "F.CrtYd")
		)
		(fp_rect
			(start -0.508 0.9398)
			(end 0.508 -0.9398)
			(stroke
				(width 0)
				(type default)
			)
			(fill no)
			(layer "F.Fab")
		)
		(pad "1" smd custom
			(at 0 -0.4445)
			(size 0.1397 0.1397)
			(layers "F.Cu" "F.Mask" "F.Paste")
			(net "SSD_PRSNT_NET7")
			(options
				(clearance outline)
				(anchor circle)
			)
			(primitives
				(gr_poly
					(pts
						(arc
							(start -0.1778 -0.2794)
							(mid -0.249642 -0.249642)
							(end -0.2794 -0.1778)
						)
						(arc
							(start -0.2794 0.1778)
							(mid -0.249642 0.249642)
							(end -0.1778 0.2794)
						)
						(arc
							(start 0.1778 0.2794)
							(mid 0.249642 0.249642)
							(end 0.2794 0.1778)
						)
						(arc
							(start 0.2794 -0.1778)
							(mid 0.249642 -0.249642)
							(end 0.1778 -0.2794)
						)
					)
					(width 0)
					(fill yes)
				)
			)
		)
		(pad "2" smd custom
			(at 0 0.4445)
			(size 0.1397 0.1397)
			(layers "F.Cu" "F.Mask" "F.Paste")
			(net "SSD_PRSNT7")
			(options
				(clearance outline)
				(anchor circle)
			)
			(primitives
				(gr_poly
					(pts
						(arc
							(start -0.1778 -0.2794)
							(mid -0.249642 -0.249642)
							(end -0.2794 -0.1778)
						)
						(arc
							(start -0.2794 0.1778)
							(mid -0.249642 0.249642)
							(end -0.1778 0.2794)
						)
						(arc
							(start 0.1778 0.2794)
							(mid 0.249642 0.249642)
							(end 0.2794 0.1778)
						)
						(arc
							(start 0.2794 -0.1778)
							(mid 0.249642 -0.249642)
							(end 0.1778 -0.2794)
						)
					)
					(width 0)
					(fill yes)
				)
			)
		)
	)
	(footprint ""
		(layer "F.Cu")
		(at 88.519 -31.877 180)
		(property "Reference" "R379"
			(at 0 0 180)
			(layer "F.SilkS")
			(hide yes)
			(effects
				(font
					(size 1.27 1.27)
				)
			)
		)
		(property "Value" "0R2J-2-GP"
			(at 0.064008 -3.993896 180)
			(unlocked yes)
			(layer "F.Fab")
			(hide yes)
			(effects
				(font
					(size 1.016 1.016)
					(thickness 0.1524)
				)
			)
		)
		(property "Device Type" "R402H16"
			(at 0.064008 -5.517896 180)
			(unlocked yes)
			(layer "F.Fab")
			(hide yes)
			(effects
				(font
					(size 1.016 1.016)
					(thickness 0.1524)
				)
			)
		)
		(duplicate_pad_numbers_are_jumpers no)
		(fp_line
			(start 0.508 -0.9398)
			(end -0.508 -0.9398)
			(stroke
				(width 0.1524)
				(type default)
			)
			(layer "F.SilkS")
		)
		(fp_line
			(start -0.508 -0.9398)
			(end -0.508 0.9398)
			(stroke
				(width 0.1524)
				(type default)
			)
			(layer "F.SilkS")
		)
		(fp_rect
			(start -0.508 0.9398)
			(end 0.508 -0.9398)
			(stroke
				(width 0)
				(type default)
			)
			(fill no)
			(layer "F.CrtYd")
		)
		(fp_rect
			(start -0.508 0.9398)
			(end 0.508 -0.9398)
			(stroke
				(width 0)
				(type default)
			)
			(fill no)
			(layer "F.Fab")
		)
		(pad "1" smd custom
			(at 0 -0.4445 180)
			(size 0.1397 0.1397)
			(layers "F.Cu" "F.Mask" "F.Paste")
			(net "VOL_SEN_SCL")
			(options
				(clearance outline)
				(anchor circle)
			)
			(primitives
				(gr_poly
					(pts
						(arc
							(start -0.1778 -0.2794)
							(mid -0.249642 -0.249642)
							(end -0.2794 -0.1778)
						)
						(arc
							(start -0.2794 0.1778)
							(mid -0.249642 0.249642)
							(end -0.1778 0.2794)
						)
						(arc
							(start 0.1778 0.2794)
							(mid 0.249642 0.249642)
							(end 0.2794 0.1778)
						)
						(arc
							(start 0.2794 -0.1778)
							(mid 0.249642 -0.249642)
							(end 0.1778 -0.2794)
						)
					)
					(width 0)
					(fill yes)
				)
			)
		)
		(pad "2" smd custom
			(at 0 0.4445 180)
			(size 0.1397 0.1397)
			(layers "F.Cu" "F.Mask" "F.Paste")
			(net "I2C_B_SCL")
			(options
				(clearance outline)
				(anchor circle)
			)
			(primitives
				(gr_poly
					(pts
						(arc
							(start -0.1778 -0.2794)
							(mid -0.249642 -0.249642)
							(end -0.2794 -0.1778)
						)
						(arc
							(start -0.2794 0.1778)
							(mid -0.249642 0.249642)
							(end -0.1778 0.2794)
						)
						(arc
							(start 0.1778 0.2794)
							(mid 0.249642 0.249642)
							(end 0.2794 0.1778)
						)
						(arc
							(start 0.2794 -0.1778)
							(mid 0.249642 -0.249642)
							(end 0.1778 -0.2794)
						)
					)
					(width 0)
					(fill yes)
				)
			)
		)
	)
)
